(kicad_pcb
	(version 20260206)
	(generator "pcbnew")
	(generator_version "10.0")
	(general
		(thickness 1.6)
		(legacy_teardrops no)
	)
	(paper "A4")
	(title_block
		(title "Bryce Canyon_R.DPB_16317-1_OCP.brd")
		(comment 1 "Bryce Canyon / footprints 1196-1202 of 2099")
	)
	(layers
		(0 "F.Cu" signal "TOP")
		(4 "In1.Cu" signal "L2GND")
		(6 "In2.Cu" signal "L3")
		(8 "In3.Cu" signal "L4VCC")
		(10 "In4.Cu" signal "L5VCC")
		(12 "In5.Cu" signal "L6")
		(14 "In6.Cu" signal "L7GND")
		(2 "B.Cu" signal "BOTTOM")
		(9 "F.Adhes" user "F.Adhesive")
		(11 "B.Adhes" user "B.Adhesive")
		(13 "F.Paste" user "Package Geometry/Pastemask Top")
		(15 "B.Paste" user "Package Geometry/Pastemask Bottom")
		(5 "F.SilkS" user "Ref Des/Silkscreen Top")
		(7 "B.SilkS" user "Ref Des/Silkscreen Bottom")
		(1 "F.Mask" user "Board Geometry/Soldermask Top")
		(3 "B.Mask" user "Board Geometry/Soldermask Bottom")
		(17 "Dwgs.User" user "User.Drawings")
		(19 "Cmts.User" user "User.Comments")
		(21 "Eco1.User" user "User.Eco1")
		(23 "Eco2.User" user "User.Eco2")
		(25 "Edge.Cuts" user "Board Geometry/Outline")
		(27 "Margin" user)
		(31 "F.CrtYd" user "Package Geometry/Place Bound Top")
		(29 "B.CrtYd" user "Package Geometry/Place Bound Bottom")
		(35 "F.Fab" user "Ref Des/Assembly Top")
		(33 "B.Fab" user "Ref Des/Assembly Bottom")
	)
	(footprint ""
		(layer "F.Cu")
		(at 17.399 -214.249)
		(property "Reference" "R205"
			(at 0 0 0)
			(layer "F.SilkS")
			(hide yes)
			(effects
				(font
					(size 1.27 1.27)
				)
			)
		)
		(property "Value" "130R3F-GP"
			(at -0.0254 -2.5146 0)
			(unlocked yes)
			(layer "F.Fab")
			(hide yes)
			(effects
				(font
					(size 1.016 1.016)
					(thickness 0.1524)
				)
			)
		)
		(property "Device Type" "R603H22"
			(at -0.0254 -4.0386 0)
			(unlocked yes)
			(layer "F.Fab")
			(hide yes)
			(effects
				(font
					(size 1.016 1.016)
					(thickness 0.1524)
				)
			)
		)
		(duplicate_pad_numbers_are_jumpers no)
		(fp_line
			(start -0.4826 0)
			(end -0.2032 0)
			(stroke
				(width 0.2032)
				(type default)
			)
			(layer "F.SilkS")
		)
		(fp_line
			(start 0.2032 0)
			(end 0.4826 0)
			(stroke
				(width 0.2032)
				(type default)
			)
			(layer "F.SilkS")
		)
		(fp_rect
			(start -0.5842 1.3335)
			(end 0.5842 -1.3335)
			(stroke
				(width 0)
				(type default)
			)
			(fill no)
			(layer "F.CrtYd")
		)
		(fp_rect
			(start -0.5842 1.3335)
			(end 0.5842 -1.3335)
			(stroke
				(width 0)
				(type default)
			)
			(fill no)
			(layer "F.Fab")
		)
		(pad "1" smd custom
			(at 0 -0.762)
			(size 0.2159 0.2159)
			(layers "F.Cu" "F.Mask" "F.Paste")
			(net "P5V_B_1")
			(options
				(clearance outline)
				(anchor circle)
			)
			(primitives
				(gr_poly
					(pts
						(arc
							(start -0.3302 -0.4318)
							(mid -0.402042 -0.402042)
							(end -0.4318 -0.3302)
						)
						(arc
							(start -0.4318 0.3302)
							(mid -0.402042 0.402042)
							(end -0.3302 0.4318)
						)
						(arc
							(start 0.3302 0.4318)
							(mid 0.402042 0.402042)
							(end 0.4318 0.3302)
						)
						(arc
							(start 0.4318 -0.3302)
							(mid 0.402042 -0.402042)
							(end 0.3302 -0.4318)
						)
					)
					(width 0)
					(fill yes)
				)
			)
		)
		(pad "2" smd custom
			(at 0 0.762)
			(size 0.2159 0.2159)
			(layers "F.Cu" "F.Mask" "F.Paste")
			(net "FLT_HDD0")
			(options
				(clearance outline)
				(anchor circle)
			)
			(primitives
				(gr_poly
					(pts
						(arc
							(start -0.3302 -0.4318)
							(mid -0.402042 -0.402042)
							(end -0.4318 -0.3302)
						)
						(arc
							(start -0.4318 0.3302)
							(mid -0.402042 0.402042)
							(end -0.3302 0.4318)
						)
						(arc
							(start 0.3302 0.4318)
							(mid 0.402042 0.402042)
							(end 0.4318 0.3302)
						)
						(arc
							(start 0.4318 -0.3302)
							(mid 0.402042 -0.402042)
							(end 0.3302 -0.4318)
						)
					)
					(width 0)
					(fill yes)
				)
			)
		)
	)
	(footprint ""
		(layer "F.Cu")
		(at 163.4998 -331.0382 180)
		(property "Reference" "R1012"
			(at 0 0 180)
			(layer "F.SilkS")
			(hide yes)
			(effects
				(font
					(size 1.27 1.27)
				)
			)
		)
		(property "Value" "D0003R4026F-GP"
			(at -6.737858 -1.79959 180)
			(unlocked yes)
			(layer "F.Fab")
			(hide yes)
			(effects
				(font
					(size 1.016 1.016)
					(thickness 0.1524)
				)
			)
		)
		(property "Device Type" "RL4026-4PH149"
			(at -6.737858 -3.32359 180)
			(unlocked yes)
			(layer "F.Fab")
			(hide yes)
			(effects
				(font
					(size 1.016 1.016)
					(thickness 0.1524)
				)
			)
		)
		(duplicate_pad_numbers_are_jumpers no)
		(fp_line
			(start 5.588 3.937)
			(end -5.588 3.937)
			(stroke
				(width 0.1524)
				(type default)
			)
			(layer "F.SilkS")
		)
		(fp_line
			(start 5.588 -3.937)
			(end 5.588 3.937)
			(stroke
				(width 0.1524)
				(type default)
			)
			(layer "F.SilkS")
		)
		(fp_line
			(start -5.588 3.937)
			(end -5.588 -3.937)
			(stroke
				(width 0.1524)
				(type default)
			)
			(layer "F.SilkS")
		)
		(fp_line
			(start -5.588 -3.937)
			(end 5.588 -3.937)
			(stroke
				(width 0.1524)
				(type default)
			)
			(layer "F.SilkS")
		)
		(fp_line
			(start -5.6769 4.0259)
			(end -4.1402 4.0259)
			(stroke
				(width 0.3302)
				(type default)
			)
			(layer "F.SilkS")
		)
		(fp_line
			(start -5.6769 2.4765)
			(end -5.6769 4.0259)
			(stroke
				(width 0.3302)
				(type default)
			)
			(layer "F.SilkS")
		)
		(fp_poly
			(pts
				(xy -4.703572 3.998468) (xy -5.289804 4.5847) (xy -4.11734 4.5847)
			)
			(stroke
				(width 0)
				(type default)
			)
			(fill yes)
			(layer "F.SilkS")
		)
		(fp_rect
			(start -5.0546 3.302)
			(end 5.0546 -3.302)
			(stroke
				(width 0)
				(type default)
			)
			(fill no)
			(layer "F.CrtYd")
		)
		(fp_poly
			(pts
				(xy -5.842 4.191) (xy -5.842 -4.191) (xy 5.842 -4.191) (xy 5.842 -0.00635) (xy 5.0546 -0.00635)
				(xy 5.0546 -3.302) (xy -5.0546 -3.302) (xy -5.0546 3.302) (xy 5.0546 3.302) (xy 5.0546 0.00635)
				(xy 5.842 0.00635) (xy 5.842 4.191)
			)
			(stroke
				(width 0)
				(type default)
			)
			(fill no)
			(layer "F.CrtYd")
		)
		(fp_rect
			(start -5.842 4.191)
			(end 5.842 -4.191)
			(stroke
				(width 0)
				(type default)
			)
			(fill no)
			(layer "F.Fab")
		)
		(pad "1" smd rect
			(at -4.115054 0.890016 180)
			(size 2.4384 5.588)
			(layers "F.Cu" "F.Mask" "F.Paste")
			(net "MB0_P12V_IN_R")
		)
		(pad "2" smd rect
			(at 4.115054 0.890016 180)
			(size 2.4384 5.588)
			(layers "F.Cu" "F.Mask" "F.Paste")
			(net "P12V_CLIP")
		)
		(pad "3" smd rect
			(at -4.115054 -3.245104 180)
			(size 2.4384 0.889)
			(layers "F.Cu" "F.Mask" "F.Paste")
			(net "MB0_CM_SENSE_R2_N")
		)
		(pad "4" smd rect
			(at 4.115054 -3.245104 180)
			(size 2.4384 0.889)
			(layers "F.Cu" "F.Mask" "F.Paste")
			(net "MB0_CM_SENSE_R2_P")
		)
		(zone
			(layer "F.Cu")
			(hatch none 0.5)
			(connect_pads
				(clearance 0)
			)
			(min_thickness 0.25)
			(keepout
				(tracks not_allowed)
				(vias allowed)
				(pads allowed)
				(copperpour not_allowed)
				(footprints allowed)
			)
			(placement
				(enabled no)
				(sheetname "")
			)
			(fill
				(thermal_gap 0.5)
				(thermal_bridge_width 0.5)
				(island_removal_mode 0)
			)
			(polygon
				(pts
					(xy 160.603946 -329.134216) (xy 158.165546 -329.134216) (xy 158.165546 -328.237596) (xy 160.603946 -328.237596)
				)
			)
		)
		(zone
			(layer "F.Cu")
			(hatch none 0.5)
			(connect_pads
				(clearance 0)
			)
			(min_thickness 0.25)
			(keepout
				(tracks allowed)
				(vias not_allowed)
				(pads allowed)
				(copperpour not_allowed)
				(footprints allowed)
			)
			(placement
				(enabled no)
				(sheetname "")
			)
			(fill
				(thermal_gap 0.5)
				(thermal_bridge_width 0.5)
				(island_removal_mode 0)
			)
			(polygon
				(pts
					(xy 160.603946 -328.237596) (xy 160.603946 -329.134216) (xy 158.165546 -329.134216) (xy 158.165546 -328.237596)
				)
			)
		)
		(zone
			(layer "F.Cu")
			(hatch none 0.5)
			(connect_pads
				(clearance 0)
			)
			(min_thickness 0.25)
			(keepout
				(tracks not_allowed)
				(vias allowed)
				(pads allowed)
				(copperpour not_allowed)
				(footprints allowed)
			)
			(placement
				(enabled no)
				(sheetname "")
			)
			(fill
				(thermal_gap 0.5)
				(thermal_bridge_width 0.5)
				(island_removal_mode 0)
			)
			(polygon
				(pts
					(xy 168.834054 -329.134216) (xy 166.395654 -329.134216) (xy 166.395654 -328.237596) (xy 168.834054 -328.237596)
				)
			)
		)
		(zone
			(layer "F.Cu")
			(hatch none 0.5)
			(connect_pads
				(clearance 0)
			)
			(min_thickness 0.25)
			(keepout
				(tracks allowed)
				(vias not_allowed)
				(pads allowed)
				(copperpour not_allowed)
				(footprints allowed)
			)
			(placement
				(enabled no)
				(sheetname "")
			)
			(fill
				(thermal_gap 0.5)
				(thermal_bridge_width 0.5)
				(island_removal_mode 0)
			)
			(polygon
				(pts
					(xy 168.834054 -328.237596) (xy 168.834054 -329.134216) (xy 166.395654 -329.134216) (xy 166.395654 -328.237596)
				)
			)
		)
	)
	(footprint ""
		(layer "F.Cu")
		(at 165.862 -376.682)
		(property "Reference" "R983"
			(at 0 0 0)
			(layer "F.SilkS")
			(hide yes)
			(effects
				(font
					(size 1.27 1.27)
				)
			)
		)
		(property "Value" "100R2D-GP"
			(at 0.064008 -3.993896 0)
			(unlocked yes)
			(layer "F.Fab")
			(hide yes)
			(effects
				(font
					(size 1.016 1.016)
					(thickness 0.1524)
				)
			)
		)
		(property "Device Type" "R402H14"
			(at 0.064008 -5.517896 0)
			(unlocked yes)
			(layer "F.Fab")
			(hide yes)
			(effects
				(font
					(size 1.016 1.016)
					(thickness 0.1524)
				)
			)
		)
		(duplicate_pad_numbers_are_jumpers no)
		(fp_line
			(start -0.508 -0.9398)
			(end -0.508 0.9398)
			(stroke
				(width 0.1524)
				(type default)
			)
			(layer "F.SilkS")
		)
		(fp_line
			(start 0.508 -0.9398)
			(end -0.508 -0.9398)
			(stroke
				(width 0.1524)
				(type default)
			)
			(layer "F.SilkS")
		)
		(fp_rect
			(start -0.508 0.9398)
			(end 0.508 -0.9398)
			(stroke
				(width 0)
				(type default)
			)
			(fill no)
			(layer "F.CrtYd")
		)
		(fp_rect
			(start -0.508 0.9398)
			(end 0.508 -0.9398)
			(stroke
				(width 0)
				(type default)
			)
			(fill no)
			(layer "F.Fab")
		)
		(pad "1" smd custom
			(at 0 -0.4445)
			(size 0.1397 0.1397)
			(layers "F.Cu" "F.Mask" "F.Paste")
			(net "GND")
			(options
				(clearance outline)
				(anchor circle)
			)
			(primitives
				(gr_poly
					(pts
						(arc
							(start -0.1778 -0.2794)
							(mid -0.249642 -0.249642)
							(end -0.2794 -0.1778)
						)
						(arc
							(start -0.2794 0.1778)
							(mid -0.249642 0.249642)
							(end -0.1778 0.2794)
						)
						(arc
							(start 0.1778 0.2794)
							(mid 0.249642 0.249642)
							(end 0.2794 0.1778)
						)
						(arc
							(start 0.2794 -0.1778)
							(mid 0.249642 -0.249642)
							(end 0.1778 -0.2794)
						)
					)
					(width 0)
					(fill yes)
				)
			)
		)
		(pad "2" smd custom
			(at 0 0.4445)
			(size 0.1397 0.1397)
			(layers "F.Cu" "F.Mask" "F.Paste")
			(net "MB0_TEMP_E")
			(options
				(clearance outline)
				(anchor circle)
			)
			(primitives
				(gr_poly
					(pts
						(arc
							(start -0.1778 -0.2794)
							(mid -0.249642 -0.249642)
							(end -0.2794 -0.1778)
						)
						(arc
							(start -0.2794 0.1778)
							(mid -0.249642 0.249642)
							(end -0.1778 0.2794)
						)
						(arc
							(start 0.1778 0.2794)
							(mid 0.249642 0.249642)
							(end 0.2794 0.1778)
						)
						(arc
							(start 0.2794 -0.1778)
							(mid 0.249642 -0.249642)
							(end 0.1778 -0.2794)
						)
					)
					(width 0)
					(fill yes)
				)
			)
		)
	)
	(footprint ""
		(layer "F.Cu")
		(at 382.315974 -39.705026)
		(property "Reference" "TP181"
			(at 0 0 0)
			(layer "F.SilkS")
			(hide yes)
			(effects
				(font
					(size 1.27 1.27)
				)
			)
		)
		(property "Value" "*"
			(at -0.0508 -1.6764 0)
			(unlocked yes)
			(layer "F.Fab")
			(hide yes)
			(effects
				(font
					(size 1.016 1.016)
					(thickness 0.1524)
				)
			)
		)
		(property "Device Type" "TPAD32"
			(at -0.0508 -3.2004 0)
			(unlocked yes)
			(layer "F.Fab")
			(hide yes)
			(effects
				(font
					(size 1.016 1.016)
					(thickness 0.1524)
				)
			)
		)
		(duplicate_pad_numbers_are_jumpers no)
		(fp_poly
			(pts
				(arc
					(start 0.4064 0)
					(mid -0.4064 0)
					(end 0.4064 0)
				)
			)
			(stroke
				(width 0)
				(type default)
			)
			(fill no)
			(layer "F.CrtYd")
		)
		(fp_poly
			(pts
				(arc
					(start 0.7112 0)
					(mid -0.7112 0)
					(end 0.7112 0)
				)
			)
			(stroke
				(width 0)
				(type default)
			)
			(fill no)
			(layer "F.Fab")
		)
		(pad "1" smd circle
			(at 0 0)
			(size 0.8128 0.8128)
			(layers "F.Cu" "F.Mask" "F.Paste")
			(net "ACT_HDD_32")
		)
	)
	(footprint ""
		(layer "F.Cu")
		(at 118.618 -157.226)
		(property "Reference" "C230"
			(at 0 0 0)
			(layer "F.SilkS")
			(hide yes)
			(effects
				(font
					(size 1.27 1.27)
				)
			)
		)
		(property "Value" "SC4D7U25V5KX-1-GP"
			(at -0.0762 -6.1214 0)
			(unlocked yes)
			(layer "F.Fab")
			(hide yes)
			(effects
				(font
					(size 1.016 1.016)
					(thickness 0.1524)
				)
			)
		)
		(property "Device Type" "C805H58"
			(at -0.0762 -8.1534 0)
			(unlocked yes)
			(layer "F.Fab")
			(hide yes)
			(effects
				(font
					(size 1.016 1.016)
					(thickness 0.1524)
				)
			)
		)
		(duplicate_pad_numbers_are_jumpers no)
		(fp_line
			(start 0.635 0)
			(end -0.635 0)
			(stroke
				(width 0.508)
				(type default)
			)
			(layer "F.SilkS")
		)
		(fp_rect
			(start -0.9652 1.778)
			(end 0.9652 -1.778)
			(stroke
				(width 0)
				(type default)
			)
			(fill no)
			(layer "F.CrtYd")
		)
		(fp_poly
			(pts
				(xy -0.9652 -1.778) (xy 0.9652 -1.778) (xy 0.9652 1.778) (xy -0.9652 1.778)
			)
			(stroke
				(width 0)
				(type default)
			)
			(fill no)
			(layer "F.Fab")
		)
		(pad "1" smd rect
			(at 0 -0.9652)
			(size 1.397 1.143)
			(layers "F.Cu" "F.Mask" "F.Paste")
			(net "P12V_HDD15")
		)
		(pad "2" smd rect
			(at 0 0.9652)
			(size 1.397 1.143)
			(layers "F.Cu" "F.Mask" "F.Paste")
			(net "GND")
		)
	)
	(footprint ""
		(layer "F.Cu")
		(at 118.237 -11.049 180)
		(property "Reference" "R705"
			(at 0 0 180)
			(layer "F.SilkS")
			(hide yes)
			(effects
				(font
					(size 1.27 1.27)
				)
			)
		)
		(property "Value" "4K7R2J-2-GP"
			(at 0.064008 -3.993896 180)
			(unlocked yes)
			(layer "F.Fab")
			(hide yes)
			(effects
				(font
					(size 1.016 1.016)
					(thickness 0.1524)
				)
			)
		)
		(property "Device Type" "R402H16"
			(at 0.064008 -5.517896 180)
			(unlocked yes)
			(layer "F.Fab")
			(hide yes)
			(effects
				(font
					(size 1.016 1.016)
					(thickness 0.1524)
				)
			)
		)
		(duplicate_pad_numbers_are_jumpers no)
		(fp_line
			(start 0.508 -0.9398)
			(end -0.508 -0.9398)
			(stroke
				(width 0.1524)
				(type default)
			)
			(layer "F.SilkS")
		)
		(fp_line
			(start -0.508 -0.9398)
			(end -0.508 0.9398)
			(stroke
				(width 0.1524)
				(type default)
			)
			(layer "F.SilkS")
		)
		(fp_rect
			(start -0.508 0.9398)
			(end 0.508 -0.9398)
			(stroke
				(width 0)
				(type default)
			)
			(fill no)
			(layer "F.CrtYd")
		)
		(fp_rect
			(start -0.508 0.9398)
			(end 0.508 -0.9398)
			(stroke
				(width 0)
				(type default)
			)
			(fill no)
			(layer "F.Fab")
		)
		(pad "1" smd custom
			(at 0 -0.4445 180)
			(size 0.1397 0.1397)
			(layers "F.Cu" "F.Mask" "F.Paste")
			(net "P12V_B")
			(options
				(clearance outline)
				(anchor circle)
			)
			(primitives
				(gr_poly
					(pts
						(arc
							(start -0.1778 -0.2794)
							(mid -0.249642 -0.249642)
							(end -0.2794 -0.1778)
						)
						(arc
							(start -0.2794 0.1778)
							(mid -0.249642 0.249642)
							(end -0.1778 0.2794)
						)
						(arc
							(start 0.1778 0.2794)
							(mid 0.249642 0.249642)
							(end 0.2794 0.1778)
						)
						(arc
							(start 0.2794 -0.1778)
							(mid 0.249642 -0.249642)
							(end 0.1778 -0.2794)
						)
					)
					(width 0)
					(fill yes)
				)
			)
		)
		(pad "2" smd custom
			(at 0 0.4445 180)
			(size 0.1397 0.1397)
			(layers "F.Cu" "F.Mask" "F.Paste")
			(net "SW_HDD_R27")
			(options
				(clearance outline)
				(anchor circle)
			)
			(primitives
				(gr_poly
					(pts
						(arc
							(start -0.1778 -0.2794)
							(mid -0.249642 -0.249642)
							(end -0.2794 -0.1778)
						)
						(arc
							(start -0.2794 0.1778)
							(mid -0.249642 0.249642)
							(end -0.1778 0.2794)
						)
						(arc
							(start 0.1778 0.2794)
							(mid 0.249642 0.249642)
							(end 0.2794 0.1778)
						)
						(arc
							(start 0.2794 -0.1778)
							(mid 0.249642 -0.249642)
							(end 0.1778 -0.2794)
						)
					)
					(width 0)
					(fill yes)
				)
			)
		)
	)
	(footprint ""
		(layer "F.Cu")
		(at 51.225196 -360.8832)
		(property "Reference" "Q127"
			(at 0 0 0)
			(layer "F.SilkS")
			(hide yes)
			(effects
				(font
					(size 1.27 1.27)
				)
			)
		)
		(property "Value" "AO4407AL-GP"
			(at -3.707384 -1.5367 0)
			(unlocked yes)
			(layer "F.Fab")
			(hide yes)
			(effects
				(font
					(size 1.016 1.016)
					(thickness 0.1524)
				)
			)
		)
		(property "Device Type" "SOIC8H69"
			(at -3.707384 -3.0607 0)
			(unlocked yes)
			(layer "F.Fab")
			(hide yes)
			(effects
				(font
					(size 1.016 1.016)
					(thickness 0.1524)
				)
			)
		)
		(duplicate_pad_numbers_are_jumpers no)
		(fp_line
			(start -2.7432 -1.4224)
			(end -2.7432 1.4224)
			(stroke
				(width 0.1524)
				(type default)
			)
			(layer "F.SilkS")
		)
		(fp_line
			(start -2.7432 1.4224)
			(end -2.6416 1.4224)
			(stroke
				(width 0.1524)
				(type default)
			)
			(layer "F.SilkS")
		)
		(fp_line
			(start -2.7432 1.4224)
			(end 2.1336 1.4224)
			(stroke
				(width 0.1524)
				(type default)
			)
			(layer "F.SilkS")
		)
		(fp_line
			(start -2.7178 -0.508)
			(end -2.1844 -0.0508)
			(stroke
				(width 0.1524)
				(type default)
			)
			(layer "F.SilkS")
		)
		(fp_line
			(start -2.6289 3.4417)
			(end -2.6289 1.4732)
			(stroke
				(width 0.381)
				(type default)
			)
			(layer "F.SilkS")
		)
		(fp_line
			(start -2.1844 -0.0508)
			(end -2.7178 0.508)
			(stroke
				(width 0.1524)
				(type default)
			)
			(layer "F.SilkS")
		)
		(fp_line
			(start 2.1336 -1.4224)
			(end -2.7432 -1.4224)
			(stroke
				(width 0.1524)
				(type default)
			)
			(layer "F.SilkS")
		)
		(fp_line
			(start 2.1336 1.4224)
			(end 2.1336 -1.4224)
			(stroke
				(width 0.1524)
				(type default)
			)
			(layer "F.SilkS")
		)
		(fp_poly
			(pts
				(xy -2.2098 -1.4224) (xy -2.2098 1.4224) (xy 2.2098 1.4224) (xy 2.2098 -1.4224)
			)
			(stroke
				(width 0)
				(type default)
			)
			(fill yes)
			(layer "F.SilkS")
		)
		(fp_rect
			(start -2.450084 2.999994)
			(end 2.450084 -2.999994)
			(stroke
				(width 0)
				(type default)
			)
			(fill no)
			(layer "F.CrtYd")
		)
		(fp_poly
			(pts
				(xy -2.8194 3.6322) (xy -2.8194 -3.6322) (xy 2.8194 -3.6322) (xy 2.8194 1.18364) (xy 2.450084 1.18364)
				(xy 2.450084 -2.999994) (xy -2.450084 -2.999994) (xy -2.450084 2.999994) (xy 2.450084 2.999994)
				(xy 2.450084 1.18618) (xy 2.8194 1.18618) (xy 2.8194 3.6322)
			)
			(stroke
				(width 0)
				(type default)
			)
			(fill no)
			(layer "F.CrtYd")
		)
		(fp_rect
			(start -2.8194 3.6322)
			(end 2.8194 -3.6322)
			(stroke
				(width 0)
				(type default)
			)
			(fill no)
			(layer "F.Fab")
		)
		(pad "1" smd rect
			(at -1.905 2.54)
			(size 0.635 1.651)
			(layers "F.Cu" "F.Mask" "F.Paste")
			(net "P12V_IN")
		)
		(pad "2" smd rect
			(at -0.635 2.54)
			(size 0.635 1.651)
			(layers "F.Cu" "F.Mask" "F.Paste")
			(net "P12V_IN")
		)
		(pad "3" smd rect
			(at 0.635 2.54)
			(size 0.635 1.651)
			(layers "F.Cu" "F.Mask" "F.Paste")
			(net "P12V_IN")
		)
		(pad "4" smd rect
			(at 1.905 2.54)
			(size 0.635 1.651)
			(layers "F.Cu" "F.Mask" "F.Paste")
			(net "GATE_FAN0_R")
		)
		(pad "5" smd rect
			(at 1.905 -2.54)
			(size 0.635 1.651)
			(layers "F.Cu" "F.Mask" "F.Paste")
			(net "P12V_FAN0")
		)
		(pad "6" smd rect
			(at 0.635 -2.54)
			(size 0.635 1.651)
			(layers "F.Cu" "F.Mask" "F.Paste")
			(net "P12V_FAN0")
		)
		(pad "7" smd rect
			(at -0.635 -2.54)
			(size 0.635 1.651)
			(layers "F.Cu" "F.Mask" "F.Paste")
			(net "P12V_FAN0")
		)
		(pad "8" smd rect
			(at -1.905 -2.54)
			(size 0.635 1.651)
			(layers "F.Cu" "F.Mask" "F.Paste")
			(net "P12V_FAN0")
		)
	)
)
